# SCM (Grand Teton) — schematic netlist excerpt (pin names and nets, part order shuffled) for the footprints in the layout excerpt that follows; sources: Cadence DE-HDL packaged netlist, KiCad conversion of 12092022_DA0F0TMDCD0_F0T_Management_Board_D_brd_V3_OCP.brd

J4  SCONN67_NASA0S6730TS67  SCONN67_NASA0-S6730-TS67 IO  pkg CON_F67S2H2D2S_P0-5W7-55_LUVXM  page 21
  \1\  = GND
  \2\  = P3V3_AUX
  \3\  = SPI_BMC_BT_WP1_N_R
  \4\  = P3V3_AUX
  \5\  = SPI_BMC_BT_WP0_N_R
  \6\  = NC
  \7\  = GND
  \16\  = BSM_PRSNT_N
  \17\  = NC
  \18\  = GND
  \19\  = RST_SPI_BMC_FLASH_R2_N
  \20\  = NC
  \21\  = RST_SPI_BMC_FLASH_R1_N
  \22\  = NC
  \23\  = GND
  \24\  = GND
  \25\  = SPI_BMC_IO1_FLASH_R
  \26\  = SPI_BMC_HOLD1_N
  \27\  = SPI_BMC_IO0_FLASH_R
  \28\  = SPI_BMC_HOLD0_N
  \29\  = GND
  \30\  = GND
  \31\  = SPI_BMC_CLK_FLASH_R
  \32\  = NC
  \33\  = GND
  \34\  = NC
  \35\  = SPI_BMC_CS1_FLASH_R_N
  \36\  = GND
  \37\  = SPI_BMC_CS0_FLASH_R_N
  \38\  = NC
  \39\  = GND
  \40\  = SMB_BMC_MM16_R1_SCL
  \41\  = NC
  \42\  = SMB_BMC_MM16_R1_SDA
  \43\  = NC
  \44\  = NC
  \45\  = GND
  \46\  = EMMC_WP
  \47\  = NC
  \48\  = NC
  \49\  = NC
  \50\  = NC
  \51\  = GND
  \52\  = EMMC_DT7_R
  \53\  = NC
  \54\  = EMMC_DT6_R
  \55\  = EMMC_CLK_R
  \56\  = EMMC_DT5_R
  \57\  = GND
  \58\  = EMMC_DT4_R
  \59\  = EMMC_CMD_R
  \60\  = NC
  \61\  = EMMC_DT3_R
  \62\  = NC
  \63\  = GND
  \64\  = NC
  \65\  = EMMC_DT2_R
  \66\  = BMC_EMMC_RST_N
  \67\  = EMMC_DT1_R
  \68\  = NC
  \69\  = GND
  \70\  = NC
  \71\  = EMMC_DT0_R
  \72\  = P3V3_AUX
  \73\  = NC
  \74\  = P3V3_AUX
  \75\  = GND
  G1  = GND
  G2  = GND

(kicad_pcb
	(version 20260206)
	(generator "pcbnew")
	(generator_version "10.0")
	(general
		(thickness 1.6)
		(legacy_teardrops no)
	)
	(paper "A4")
	(title_block
		(title "12092022_DA0F0TMDCD0_F0T_Management_Board_D_brd_V3_OCP.brd")
		(comment 1 "Grand Teton / footprint 610 of 1440 (J4), pads 50-71 of 71")
	)
	(layers
		(0 "F.Cu" signal "TOP")
		(4 "In1.Cu" signal "GND")
		(6 "In2.Cu" signal "IN1")
		(8 "In3.Cu" signal "GND1")
		(10 "In4.Cu" signal "IN2")
		(12 "In5.Cu" signal "VCC")
		(14 "In6.Cu" signal "VCC1")
		(16 "In7.Cu" signal "IN3")
		(18 "In8.Cu" signal "GND2")
		(20 "In9.Cu" signal "IN4")
		(22 "In10.Cu" signal "GND3")
		(2 "B.Cu" signal "BOTTOM")
		(9 "F.Adhes" user "F.Adhesive")
		(11 "B.Adhes" user "B.Adhesive")
		(13 "F.Paste" user "Package Geometry/Pastemask Top")
		(15 "B.Paste" user "Package Geometry/Pastemask Bottom")
		(5 "F.SilkS" user "Ref Des/Silkscreen Top")
		(7 "B.SilkS" user "Ref Des/Silkscreen Bottom")
		(1 "F.Mask" user "Board Geometry/Soldermask Top")
		(3 "B.Mask" user "Board Geometry/Soldermask Bottom")
		(17 "Dwgs.User" user "User.Drawings")
		(19 "Cmts.User" user "User.Comments")
		(21 "Eco1.User" user "User.Eco1")
		(23 "Eco2.User" user "User.Eco2")
		(25 "Edge.Cuts" user "Board Geometry/Outline")
		(27 "Margin" user)
		(31 "F.CrtYd" user "Package Geometry/Place Bound Top")
		(29 "B.CrtYd" user "Package Geometry/Place Bound Bottom")
		(35 "F.Fab" user "Ref Des/Assembly Top")
		(33 "B.Fab" user "Ref Des/Assembly Bottom")
	)
	(footprint ""
		(layer "F.Cu")
		(at 26.75001 -77.16012 90)
		(property "Reference" "J4"
			(at -3.798062 -11.674348 90)
			(unlocked yes)
			(layer "F.SilkS")
			(effects
				(font
					(size 0.7874 0.5842)
					(thickness 0.1524)
				)
				(justify left)
			)
		)
		(property "Value" ""
			(at 0 0 90)
			(layer "F.Fab")
			(effects
				(font
					(size 1.27 1.27)
				)
			)
		)
		(duplicate_pad_numbers_are_jumpers no)
		(pad "56" smd rect
			(at -3.799586 4.500118)
			(size 0.2794 1.6002)
			(layers "F.Cu" "F.Mask" "F.Paste")
			(net "EMMC_DT5_R")
		)
		(pad "57" smd rect
			(at 3.750056 4.750054)
			(size 0.2794 1.6002)
			(layers "F.Cu" "F.Mask" "F.Paste")
			(net "GND")
		)
		(pad "58" smd rect
			(at -3.799586 4.99999)
			(size 0.2794 1.6002)
			(layers "F.Cu" "F.Mask" "F.Paste")
			(net "EMMC_DT4_R")
		)
		(pad "59" smd rect
			(at 3.750056 5.249926)
			(size 0.2794 1.6002)
			(layers "F.Cu" "F.Mask" "F.Paste")
			(net "EMMC_CMD_R")
		)
		(pad "60" smd rect
			(at -3.799586 5.500116)
			(size 0.2794 1.6002)
			(layers "F.Cu" "F.Mask" "F.Paste")
			(net "Net_1206")
		)
		(pad "61" smd rect
			(at 3.750056 5.750052)
			(size 0.2794 1.6002)
			(layers "F.Cu" "F.Mask" "F.Paste")
			(net "EMMC_DT3_R")
		)
		(pad "62" smd rect
			(at -3.799586 5.999988)
			(size 0.2794 1.6002)
			(layers "F.Cu" "F.Mask" "F.Paste")
			(net "Net_1205")
		)
		(pad "63" smd rect
			(at 3.750056 6.249924)
			(size 0.2794 1.6002)
			(layers "F.Cu" "F.Mask" "F.Paste")
			(net "GND")
		)
		(pad "64" smd rect
			(at -3.799586 6.500114)
			(size 0.2794 1.6002)
			(layers "F.Cu" "F.Mask" "F.Paste")
			(net "Net_1204")
		)
		(pad "65" smd rect
			(at 3.750056 6.75005)
			(size 0.2794 1.6002)
			(layers "F.Cu" "F.Mask" "F.Paste")
			(net "EMMC_DT2_R")
		)
		(pad "66" smd rect
			(at -3.799586 6.999986)
			(size 0.2794 1.6002)
			(layers "F.Cu" "F.Mask" "F.Paste")
			(net "BMC_EMMC_RST_N")
		)
		(pad "67" smd rect
			(at 3.750056 7.249922)
			(size 0.2794 1.6002)
			(layers "F.Cu" "F.Mask" "F.Paste")
			(net "EMMC_DT1_R")
		)
		(pad "68" smd rect
			(at -3.799586 7.500112)
			(size 0.2794 1.6002)
			(layers "F.Cu" "F.Mask" "F.Paste")
			(net "Net_1203")
		)
		(pad "69" smd rect
			(at 3.750056 7.750048)
			(size 0.2794 1.6002)
			(layers "F.Cu" "F.Mask" "F.Paste")
			(net "GND")
		)
		(pad "70" smd rect
			(at -3.799586 7.999984)
			(size 0.2794 1.6002)
			(layers "F.Cu" "F.Mask" "F.Paste")
			(net "Net_1202")
		)
		(pad "71" smd rect
			(at 3.750056 8.24992)
			(size 0.2794 1.6002)
			(layers "F.Cu" "F.Mask" "F.Paste")
			(net "EMMC_DT0_R")
		)
		(pad "72" smd rect
			(at -3.799586 8.50011)
			(size 0.2794 1.6002)
			(layers "F.Cu" "F.Mask" "F.Paste")
			(net "P3V3_AUX")
		)
		(pad "73" smd rect
			(at 3.750056 8.750046)
			(size 0.2794 1.6002)
			(layers "F.Cu" "F.Mask" "F.Paste")
			(net "Net_1201")
		)
		(pad "74" smd rect
			(at -3.799586 8.999982)
			(size 0.2794 1.6002)
			(layers "F.Cu" "F.Mask" "F.Paste")
			(net "P3V3_AUX")
		)
		(pad "75" smd rect
			(at 3.750056 9.249918)
			(size 0.2794 1.6002)
			(layers "F.Cu" "F.Mask" "F.Paste")
			(net "GND")
		)
		(pad "G1" smd rect
			(at 2.975102 -10.349992)
			(size 1.2446 2.794)
			(layers "F.Cu" "F.Mask" "F.Paste")
			(net "GND")
		)
		(pad "G2" smd rect
			(at 2.975102 10.349992)
			(size 1.2446 2.794)
			(layers "F.Cu" "F.Mask" "F.Paste")
			(net "GND")
		)
	)
)
